(kicad_pcb
	(version 20260206)
	(generator "pcbnew")
	(generator_version "10.0")
	(general
		(thickness 1.6)
		(legacy_teardrops no)
	)
	(paper "A4")
	(title_block
		(title "baseboard — 13948-1b.1110WZS1818.brd")
		(comment 1 "Honey Badger (Wiwynn) / footprints 2494-2500 of 2523")
	)
	(layers
		(0 "F.Cu" signal "TOP")
		(4 "In1.Cu" signal "L2GND")
		(6 "In2.Cu" signal "L3")
		(8 "In3.Cu" signal "L4VCC")
		(10 "In4.Cu" signal "L5VCC")
		(12 "In5.Cu" signal "L6")
		(14 "In6.Cu" signal "L7GND")
		(2 "B.Cu" signal "BOTTOM")
		(9 "F.Adhes" user "F.Adhesive")
		(11 "B.Adhes" user "B.Adhesive")
		(13 "F.Paste" user "Package Geometry/Pastemask Top")
		(15 "B.Paste" user "Package Geometry/Pastemask Bottom")
		(5 "F.SilkS" user "Ref Des/Silkscreen Top")
		(7 "B.SilkS" user "Ref Des/Silkscreen Bottom")
		(1 "F.Mask" user "Board Geometry/Soldermask Top")
		(3 "B.Mask" user "Board Geometry/Soldermask Bottom")
		(17 "Dwgs.User" user "User.Drawings")
		(19 "Cmts.User" user "User.Comments")
		(21 "Eco1.User" user "User.Eco1")
		(23 "Eco2.User" user "User.Eco2")
		(25 "Edge.Cuts" user "Board Geometry/Outline")
		(27 "Margin" user)
		(31 "F.CrtYd" user "Package Geometry/Place Bound Top")
		(29 "B.CrtYd" user "Package Geometry/Place Bound Bottom")
		(35 "F.Fab" user "Ref Des/Assembly Top")
		(33 "B.Fab" user "Ref Des/Assembly Bottom")
	)
	(footprint ""
		(layer "B.Cu")
		(at 120.015 -41.148 -90)
		(property "Reference" "SR623"
			(at 0 0 90)
			(layer "B.SilkS")
			(hide yes)
			(effects
				(font
					(size 1.27 1.27)
				)
				(justify mirror)
			)
		)
		(property "Value" "2K2R2F-GP"
			(at -0.064008 -3.993896 270)
			(unlocked yes)
			(layer "B.Fab")
			(hide yes)
			(effects
				(font
					(size 1.016 1.016)
					(thickness 0.1524)
				)
				(justify mirror)
			)
		)
		(property "Device Type" "R402H16"
			(at -0.064008 -5.517896 270)
			(unlocked yes)
			(layer "B.Fab")
			(hide yes)
			(effects
				(font
					(size 1.016 1.016)
					(thickness 0.1524)
				)
				(justify mirror)
			)
		)
		(duplicate_pad_numbers_are_jumpers no)
		(fp_line
			(start -0.508 -0.9398)
			(end 0.508 -0.9398)
			(stroke
				(width 0.1524)
				(type default)
			)
			(layer "B.SilkS")
		)
		(fp_line
			(start 0.508 -0.9398)
			(end 0.508 0.9398)
			(stroke
				(width 0.1524)
				(type default)
			)
			(layer "B.SilkS")
		)
		(fp_rect
			(start 0.508 0.9398)
			(end -0.508 -0.9398)
			(stroke
				(width 0)
				(type default)
			)
			(fill no)
			(layer "B.CrtYd")
		)
		(fp_rect
			(start 0.508 0.9398)
			(end -0.508 -0.9398)
			(stroke
				(width 0)
				(type default)
			)
			(fill no)
			(layer "B.Fab")
		)
		(pad "1" smd custom
			(at 0 -0.4445 90)
			(size 0.1397 0.1397)
			(layers "B.Cu" "B.Mask" "B.Paste")
			(net "P1V8_C")
			(options
				(clearance outline)
				(anchor circle)
			)
			(primitives
				(gr_poly
					(pts
						(arc
							(start -0.1778 0.2794)
							(mid -0.249642 0.249642)
							(end -0.2794 0.1778)
						)
						(arc
							(start -0.2794 -0.1778)
							(mid -0.249642 -0.249642)
							(end -0.1778 -0.2794)
						)
						(arc
							(start 0.1778 -0.2794)
							(mid 0.249642 -0.249642)
							(end 0.2794 -0.1778)
						)
						(arc
							(start 0.2794 0.1778)
							(mid 0.249642 0.249642)
							(end 0.1778 0.2794)
						)
					)
					(width 0)
					(fill yes)
				)
			)
		)
		(pad "2" smd custom
			(at 0 0.4445 90)
			(size 0.1397 0.1397)
			(layers "B.Cu" "B.Mask" "B.Paste")
			(net "IOC_SDA_3")
			(options
				(clearance outline)
				(anchor circle)
			)
			(primitives
				(gr_poly
					(pts
						(arc
							(start -0.1778 0.2794)
							(mid -0.249642 0.249642)
							(end -0.2794 0.1778)
						)
						(arc
							(start -0.2794 -0.1778)
							(mid -0.249642 -0.249642)
							(end -0.1778 -0.2794)
						)
						(arc
							(start 0.1778 -0.2794)
							(mid 0.249642 -0.249642)
							(end 0.2794 -0.1778)
						)
						(arc
							(start 0.2794 0.1778)
							(mid 0.249642 0.249642)
							(end 0.1778 0.2794)
						)
					)
					(width 0)
					(fill yes)
				)
			)
		)
	)
	(footprint ""
		(layer "B.Cu")
		(at 88.52916 -53.086)
		(property "Reference" "SR631"
			(at 0 0 0)
			(layer "B.SilkS")
			(hide yes)
			(effects
				(font
					(size 1.27 1.27)
				)
				(justify mirror)
			)
		)
		(property "Value" "2K2R2F-GP"
			(at -0.064008 -3.993896 0)
			(unlocked yes)
			(layer "B.Fab")
			(hide yes)
			(effects
				(font
					(size 1.016 1.016)
					(thickness 0.1524)
				)
				(justify mirror)
			)
		)
		(property "Device Type" "R402H16"
			(at -0.064008 -5.517896 0)
			(unlocked yes)
			(layer "B.Fab")
			(hide yes)
			(effects
				(font
					(size 1.016 1.016)
					(thickness 0.1524)
				)
				(justify mirror)
			)
		)
		(duplicate_pad_numbers_are_jumpers no)
		(fp_line
			(start -0.508 -0.9398)
			(end 0.508 -0.9398)
			(stroke
				(width 0.1524)
				(type default)
			)
			(layer "B.SilkS")
		)
		(fp_line
			(start 0.508 -0.9398)
			(end 0.508 0.9398)
			(stroke
				(width 0.1524)
				(type default)
			)
			(layer "B.SilkS")
		)
		(fp_rect
			(start 0.508 0.9398)
			(end -0.508 -0.9398)
			(stroke
				(width 0)
				(type default)
			)
			(fill no)
			(layer "B.CrtYd")
		)
		(fp_rect
			(start 0.508 0.9398)
			(end -0.508 -0.9398)
			(stroke
				(width 0)
				(type default)
			)
			(fill no)
			(layer "B.Fab")
		)
		(pad "1" smd custom
			(at 0 -0.4445 180)
			(size 0.1397 0.1397)
			(layers "B.Cu" "B.Mask" "B.Paste")
			(net "P1V8_C")
			(options
				(clearance outline)
				(anchor circle)
			)
			(primitives
				(gr_poly
					(pts
						(arc
							(start -0.1778 0.2794)
							(mid -0.249642 0.249642)
							(end -0.2794 0.1778)
						)
						(arc
							(start -0.2794 -0.1778)
							(mid -0.249642 -0.249642)
							(end -0.1778 -0.2794)
						)
						(arc
							(start 0.1778 -0.2794)
							(mid 0.249642 -0.249642)
							(end 0.2794 -0.1778)
						)
						(arc
							(start 0.2794 0.1778)
							(mid 0.249642 0.249642)
							(end 0.1778 0.2794)
						)
					)
					(width 0)
					(fill yes)
				)
			)
		)
		(pad "2" smd custom
			(at 0 0.4445 180)
			(size 0.1397 0.1397)
			(layers "B.Cu" "B.Mask" "B.Paste")
			(net "SIO_DIN_1")
			(options
				(clearance outline)
				(anchor circle)
			)
			(primitives
				(gr_poly
					(pts
						(arc
							(start -0.1778 0.2794)
							(mid -0.249642 0.249642)
							(end -0.2794 0.1778)
						)
						(arc
							(start -0.2794 -0.1778)
							(mid -0.249642 -0.249642)
							(end -0.1778 -0.2794)
						)
						(arc
							(start 0.1778 -0.2794)
							(mid 0.249642 -0.249642)
							(end 0.2794 -0.1778)
						)
						(arc
							(start 0.2794 0.1778)
							(mid 0.249642 0.249642)
							(end 0.1778 0.2794)
						)
					)
					(width 0)
					(fill yes)
				)
			)
		)
	)
	(footprint ""
		(layer "B.Cu")
		(at 340.995 -101.473 -90)
		(property "Reference" "PR14"
			(at 0 0 90)
			(layer "B.SilkS")
			(hide yes)
			(effects
				(font
					(size 1.27 1.27)
				)
				(justify mirror)
			)
		)
		(property "Value" "2KR2F-3-GP"
			(at -0.064008 -3.993896 270)
			(unlocked yes)
			(layer "B.Fab")
			(hide yes)
			(effects
				(font
					(size 1.016 1.016)
					(thickness 0.1524)
				)
				(justify mirror)
			)
		)
		(property "Device Type" "R402H16"
			(at -0.064008 -5.517896 270)
			(unlocked yes)
			(layer "B.Fab")
			(hide yes)
			(effects
				(font
					(size 1.016 1.016)
					(thickness 0.1524)
				)
				(justify mirror)
			)
		)
		(duplicate_pad_numbers_are_jumpers no)
		(fp_line
			(start -0.508 -0.9398)
			(end 0.508 -0.9398)
			(stroke
				(width 0.1524)
				(type default)
			)
			(layer "B.SilkS")
		)
		(fp_line
			(start 0.508 -0.9398)
			(end 0.508 0.9398)
			(stroke
				(width 0.1524)
				(type default)
			)
			(layer "B.SilkS")
		)
		(fp_rect
			(start 0.508 0.9398)
			(end -0.508 -0.9398)
			(stroke
				(width 0)
				(type default)
			)
			(fill no)
			(layer "B.CrtYd")
		)
		(fp_rect
			(start 0.508 0.9398)
			(end -0.508 -0.9398)
			(stroke
				(width 0)
				(type default)
			)
			(fill no)
			(layer "B.Fab")
		)
		(pad "1" smd custom
			(at 0 -0.4445 90)
			(size 0.1397 0.1397)
			(layers "B.Cu" "B.Mask" "B.Paste")
			(net "P5V_STBY_SW")
			(options
				(clearance outline)
				(anchor circle)
			)
			(primitives
				(gr_poly
					(pts
						(arc
							(start -0.1778 0.2794)
							(mid -0.249642 0.249642)
							(end -0.2794 0.1778)
						)
						(arc
							(start -0.2794 -0.1778)
							(mid -0.249642 -0.249642)
							(end -0.1778 -0.2794)
						)
						(arc
							(start 0.1778 -0.2794)
							(mid 0.249642 -0.249642)
							(end 0.2794 -0.1778)
						)
						(arc
							(start 0.2794 0.1778)
							(mid 0.249642 0.249642)
							(end 0.1778 0.2794)
						)
					)
					(width 0)
					(fill yes)
				)
			)
		)
		(pad "2" smd custom
			(at 0 0.4445 90)
			(size 0.1397 0.1397)
			(layers "B.Cu" "B.Mask" "B.Paste")
			(net "P5V_STBY_VFB_R")
			(options
				(clearance outline)
				(anchor circle)
			)
			(primitives
				(gr_poly
					(pts
						(arc
							(start -0.1778 0.2794)
							(mid -0.249642 0.249642)
							(end -0.2794 0.1778)
						)
						(arc
							(start -0.2794 -0.1778)
							(mid -0.249642 -0.249642)
							(end -0.1778 -0.2794)
						)
						(arc
							(start 0.1778 -0.2794)
							(mid 0.249642 -0.249642)
							(end 0.2794 -0.1778)
						)
						(arc
							(start 0.2794 0.1778)
							(mid 0.249642 0.249642)
							(end 0.1778 0.2794)
						)
					)
					(width 0)
					(fill yes)
				)
			)
		)
	)
	(footprint ""
		(layer "B.Cu")
		(at 318.008 -173.609 90)
		(property "Reference" "R469"
			(at 0 0 90)
			(layer "B.SilkS")
			(hide yes)
			(effects
				(font
					(size 1.27 1.27)
				)
				(justify mirror)
			)
		)
		(property "Value" "0R2J-2-GP"
			(at -0.064008 -3.993896 90)
			(unlocked yes)
			(layer "B.Fab")
			(hide yes)
			(effects
				(font
					(size 1.016 1.016)
					(thickness 0.1524)
				)
				(justify mirror)
			)
		)
		(property "Device Type" "R402H16"
			(at -0.064008 -5.517896 90)
			(unlocked yes)
			(layer "B.Fab")
			(hide yes)
			(effects
				(font
					(size 1.016 1.016)
					(thickness 0.1524)
				)
				(justify mirror)
			)
		)
		(duplicate_pad_numbers_are_jumpers no)
		(fp_line
			(start 0.508 -0.9398)
			(end 0.508 0.9398)
			(stroke
				(width 0.1524)
				(type default)
			)
			(layer "B.SilkS")
		)
		(fp_line
			(start -0.508 -0.9398)
			(end 0.508 -0.9398)
			(stroke
				(width 0.1524)
				(type default)
			)
			(layer "B.SilkS")
		)
		(fp_rect
			(start 0.508 0.9398)
			(end -0.508 -0.9398)
			(stroke
				(width 0)
				(type default)
			)
			(fill no)
			(layer "B.CrtYd")
		)
		(fp_rect
			(start 0.508 0.9398)
			(end -0.508 -0.9398)
			(stroke
				(width 0)
				(type default)
			)
			(fill no)
			(layer "B.Fab")
		)
		(pad "1" smd custom
			(at 0 -0.4445 270)
			(size 0.1397 0.1397)
			(layers "B.Cu" "B.Mask" "B.Paste")
			(net "BMC0_SMB14_SDA")
			(options
				(clearance outline)
				(anchor circle)
			)
			(primitives
				(gr_poly
					(pts
						(arc
							(start -0.1778 0.2794)
							(mid -0.249642 0.249642)
							(end -0.2794 0.1778)
						)
						(arc
							(start -0.2794 -0.1778)
							(mid -0.249642 -0.249642)
							(end -0.1778 -0.2794)
						)
						(arc
							(start 0.1778 -0.2794)
							(mid 0.249642 -0.249642)
							(end 0.2794 -0.1778)
						)
						(arc
							(start 0.2794 0.1778)
							(mid 0.249642 0.249642)
							(end 0.1778 0.2794)
						)
					)
					(width 0)
					(fill yes)
				)
			)
		)
		(pad "2" smd custom
			(at 0 0.4445 270)
			(size 0.1397 0.1397)
			(layers "B.Cu" "B.Mask" "B.Paste")
			(net "EXP_IOC_BMC_SDA_14")
			(options
				(clearance outline)
				(anchor circle)
			)
			(primitives
				(gr_poly
					(pts
						(arc
							(start -0.1778 0.2794)
							(mid -0.249642 0.249642)
							(end -0.2794 0.1778)
						)
						(arc
							(start -0.2794 -0.1778)
							(mid -0.249642 -0.249642)
							(end -0.1778 -0.2794)
						)
						(arc
							(start 0.1778 -0.2794)
							(mid 0.249642 -0.249642)
							(end 0.2794 -0.1778)
						)
						(arc
							(start 0.2794 0.1778)
							(mid 0.249642 0.249642)
							(end 0.1778 0.2794)
						)
					)
					(width 0)
					(fill yes)
				)
			)
		)
	)
	(footprint ""
		(layer "B.Cu")
		(at 90.68816 -41.148 90)
		(property "Reference" "SC940"
			(at 0 0 90)
			(layer "B.SilkS")
			(hide yes)
			(effects
				(font
					(size 1.27 1.27)
				)
				(justify mirror)
			)
		)
		(property "Value" "SCD1U6D3V1KX-GP"
			(at 2.8321 -1.7399 90)
			(unlocked yes)
			(layer "B.Fab")
			(hide yes)
			(effects
				(font
					(size 1.016 1.016)
					(thickness 0.1524)
				)
				(justify mirror)
			)
		)
		(property "Device Type" "C0201H13"
			(at 2.8321 -3.2639 90)
			(unlocked yes)
			(layer "B.Fab")
			(hide yes)
			(effects
				(font
					(size 1.016 1.016)
					(thickness 0.1524)
				)
				(justify mirror)
			)
		)
		(duplicate_pad_numbers_are_jumpers no)
		(fp_rect
			(start 0.2794 0.6477)
			(end -0.2794 -0.6477)
			(stroke
				(width 0)
				(type default)
			)
			(fill no)
			(layer "B.CrtYd")
		)
		(fp_rect
			(start 0.2794 0.6477)
			(end -0.2794 -0.6477)
			(stroke
				(width 0)
				(type default)
			)
			(fill no)
			(layer "B.Fab")
		)
		(pad "1" smd custom
			(at 0 -0.2794 270)
			(size 0.0762 0.0762)
			(layers "B.Cu" "B.Mask" "B.Paste")
			(net "SAS0_VDDH")
			(options
				(clearance outline)
				(anchor circle)
			)
			(primitives
				(gr_poly
					(pts
						(arc
							(start 0.1524 0.127)
							(mid 0.137521 0.162921)
							(end 0.1016 0.1778)
						)
						(arc
							(start -0.1016 0.1778)
							(mid -0.137521 0.162921)
							(end -0.1524 0.127)
						)
						(arc
							(start -0.1524 -0.127)
							(mid -0.137521 -0.162921)
							(end -0.1016 -0.1778)
						)
						(arc
							(start 0.1016 -0.1778)
							(mid 0.137521 -0.162921)
							(end 0.1524 -0.127)
						)
					)
					(width 0)
					(fill yes)
				)
			)
		)
		(pad "2" smd custom
			(at 0 0.2794 270)
			(size 0.0762 0.0762)
			(layers "B.Cu" "B.Mask" "B.Paste")
			(net "GND")
			(options
				(clearance outline)
				(anchor circle)
			)
			(primitives
				(gr_poly
					(pts
						(arc
							(start 0.1524 0.127)
							(mid 0.137521 0.162921)
							(end 0.1016 0.1778)
						)
						(arc
							(start -0.1016 0.1778)
							(mid -0.137521 0.162921)
							(end -0.1524 0.127)
						)
						(arc
							(start -0.1524 -0.127)
							(mid -0.137521 -0.162921)
							(end -0.1016 -0.1778)
						)
						(arc
							(start 0.1016 -0.1778)
							(mid 0.137521 -0.162921)
							(end 0.1524 -0.127)
						)
					)
					(width 0)
					(fill yes)
				)
			)
		)
	)
	(footprint ""
		(layer "B.Cu")
		(at 265.811 -16.891 180)
		(property "Reference" "C337"
			(at 0 0 0)
			(layer "B.SilkS")
			(hide yes)
			(effects
				(font
					(size 1.27 1.27)
				)
				(justify mirror)
			)
		)
		(property "Value" "SC1U10V3KX-4GP-U"
			(at 0 -2.8194 180)
			(unlocked yes)
			(layer "B.Fab")
			(hide yes)
			(effects
				(font
					(size 1.016 1.016)
					(thickness 0.1524)
				)
				(justify mirror)
			)
		)
		(property "Device Type" "C603H36"
			(at 0 -4.3434 180)
			(unlocked yes)
			(layer "B.Fab")
			(hide yes)
			(effects
				(font
					(size 1.016 1.016)
					(thickness 0.1524)
				)
				(justify mirror)
			)
		)
		(duplicate_pad_numbers_are_jumpers no)
		(fp_line
			(start -0.508 0)
			(end 0.508 0)
			(stroke
				(width 0.2032)
				(type default)
			)
			(layer "B.SilkS")
		)
		(fp_rect
			(start 0.5842 1.3335)
			(end -0.5842 -1.3335)
			(stroke
				(width 0)
				(type default)
			)
			(fill no)
			(layer "B.CrtYd")
		)
		(fp_rect
			(start 0.5842 1.3335)
			(end -0.5842 -1.3335)
			(stroke
				(width 0)
				(type default)
			)
			(fill no)
			(layer "B.Fab")
		)
		(pad "1" smd custom
			(at 0 -0.762)
			(size 0.2159 0.2159)
			(layers "B.Cu" "B.Mask" "B.Paste")
			(net "P5V_USB")
			(options
				(clearance outline)
				(anchor circle)
			)
			(primitives
				(gr_poly
					(pts
						(arc
							(start -0.3302 0.4318)
							(mid -0.402042 0.402042)
							(end -0.4318 0.3302)
						)
						(arc
							(start -0.4318 -0.3302)
							(mid -0.402042 -0.402042)
							(end -0.3302 -0.4318)
						)
						(arc
							(start 0.3302 -0.4318)
							(mid 0.402042 -0.402042)
							(end 0.4318 -0.3302)
						)
						(arc
							(start 0.4318 0.3302)
							(mid 0.402042 0.402042)
							(end 0.3302 0.4318)
						)
					)
					(width 0)
					(fill yes)
				)
			)
		)
		(pad "2" smd custom
			(at 0 0.762)
			(size 0.2159 0.2159)
			(layers "B.Cu" "B.Mask" "B.Paste")
			(net "GND")
			(options
				(clearance outline)
				(anchor circle)
			)
			(primitives
				(gr_poly
					(pts
						(arc
							(start -0.3302 0.4318)
							(mid -0.402042 0.402042)
							(end -0.4318 0.3302)
						)
						(arc
							(start -0.4318 -0.3302)
							(mid -0.402042 -0.402042)
							(end -0.3302 -0.4318)
						)
						(arc
							(start 0.3302 -0.4318)
							(mid 0.402042 -0.402042)
							(end 0.4318 -0.3302)
						)
						(arc
							(start 0.4318 0.3302)
							(mid 0.402042 0.402042)
							(end 0.3302 0.4318)
						)
					)
					(width 0)
					(fill yes)
				)
			)
		)
	)
	(footprint ""
		(layer "B.Cu")
		(at 290.068 -203.835 180)
		(property "Reference" "C197"
			(at 0 0 0)
			(layer "B.SilkS")
			(hide yes)
			(effects
				(font
					(size 1.27 1.27)
				)
				(justify mirror)
			)
		)
		(property "Value" "SC1U10V3KX-4GP-U"
			(at 0 -2.8194 180)
			(unlocked yes)
			(layer "B.Fab")
			(hide yes)
			(effects
				(font
					(size 1.016 1.016)
					(thickness 0.1524)
				)
				(justify mirror)
			)
		)
		(property "Device Type" "C603H36"
			(at 0 -4.3434 180)
			(unlocked yes)
			(layer "B.Fab")
			(hide yes)
			(effects
				(font
					(size 1.016 1.016)
					(thickness 0.1524)
				)
				(justify mirror)
			)
		)
		(duplicate_pad_numbers_are_jumpers no)
		(fp_line
			(start -0.508 0)
			(end 0.508 0)
			(stroke
				(width 0.2032)
				(type default)
			)
			(layer "B.SilkS")
		)
		(fp_rect
			(start 0.5842 1.3335)
			(end -0.5842 -1.3335)
			(stroke
				(width 0)
				(type default)
			)
			(fill no)
			(layer "B.CrtYd")
		)
		(fp_rect
			(start 0.5842 1.3335)
			(end -0.5842 -1.3335)
			(stroke
				(width 0)
				(type default)
			)
			(fill no)
			(layer "B.Fab")
		)
		(pad "1" smd custom
			(at 0 -0.762)
			(size 0.2159 0.2159)
			(layers "B.Cu" "B.Mask" "B.Paste")
			(net "P1V53_STBY")
			(options
				(clearance outline)
				(anchor circle)
			)
			(primitives
				(gr_poly
					(pts
						(arc
							(start -0.3302 0.4318)
							(mid -0.402042 0.402042)
							(end -0.4318 0.3302)
						)
						(arc
							(start -0.4318 -0.3302)
							(mid -0.402042 -0.402042)
							(end -0.3302 -0.4318)
						)
						(arc
							(start 0.3302 -0.4318)
							(mid 0.402042 -0.402042)
							(end 0.4318 -0.3302)
						)
						(arc
							(start 0.4318 0.3302)
							(mid 0.402042 0.402042)
							(end 0.3302 0.4318)
						)
					)
					(width 0)
					(fill yes)
				)
			)
		)
		(pad "2" smd custom
			(at 0 0.762)
			(size 0.2159 0.2159)
			(layers "B.Cu" "B.Mask" "B.Paste")
			(net "GND")
			(options
				(clearance outline)
				(anchor circle)
			)
			(primitives
				(gr_poly
					(pts
						(arc
							(start -0.3302 0.4318)
							(mid -0.402042 0.402042)
							(end -0.4318 0.3302)
						)
						(arc
							(start -0.4318 -0.3302)
							(mid -0.402042 -0.402042)
							(end -0.3302 -0.4318)
						)
						(arc
							(start 0.3302 -0.4318)
							(mid 0.402042 -0.402042)
							(end 0.4318 -0.3302)
						)
						(arc
							(start 0.4318 0.3302)
							(mid 0.402042 0.402042)
							(end 0.3302 0.4318)
						)
					)
					(width 0)
					(fill yes)
				)
			)
		)
	)
)
